# S9S_MB_2U (Grand Teton) — schematic netlist excerpt (pin names and nets, part order shuffled) for the footprints in the layout excerpt that follows; sources: Cadence DE-HDL packaged netlist, KiCad conversion of 03242023_DA0F0TMBIJ0_F0T_Motherboard_J_brd_V01_OCP.brd

C2332  Q_CAP  10UF 6.3V 20% X6S  pkg C0603  page 211 : A = P3V3_9ZXL045_VDDR ; B = GND
C1942  Q_CAP  0.1UF 25V 10% X7R  pkg 0402  page 217 : A = P3V3_AUX_FPGA_VCCIO4 ; B = GND
PC433  Q_CAP  22UF 16V 20% X6S  pkg C0805  page 294 : A = SW_P12V_PVCCINFAON_CPU1_FLT ; B = GND

(kicad_pcb
	(version 20260206)
	(generator "pcbnew")
	(generator_version "10.0")
	(general
		(thickness 1.6)
		(legacy_teardrops no)
	)
	(paper "A4")
	(title_block
		(title "03242023_DA0F0TMBIJ0_F0T_Motherboard_J_brd_V01_OCP.brd")
		(comment 1 "Grand Teton / footprints 4480-4482 of 6105")
	)
	(layers
		(0 "F.Cu" signal "TOP")
		(4 "In1.Cu" signal "GND")
		(6 "In2.Cu" signal "IN1")
		(8 "In3.Cu" signal "GND1")
		(10 "In4.Cu" signal "IN2")
		(12 "In5.Cu" signal "GND2")
		(14 "In6.Cu" signal "IN3")
		(16 "In7.Cu" signal "GND3")
		(18 "In8.Cu" signal "VCC")
		(20 "In9.Cu" signal "VCC1")
		(22 "In10.Cu" signal "GND4")
		(24 "In11.Cu" signal "IN4")
		(26 "In12.Cu" signal "GND5")
		(28 "In13.Cu" signal "IN5")
		(30 "In14.Cu" signal "GND6")
		(32 "In15.Cu" signal "IN6")
		(34 "In16.Cu" signal "GND7")
		(2 "B.Cu" signal "BOTTOM")
		(9 "F.Adhes" user "F.Adhesive")
		(11 "B.Adhes" user "B.Adhesive")
		(13 "F.Paste" user "Package Geometry/Pastemask Top")
		(15 "B.Paste" user "Package Geometry/Pastemask Bottom")
		(5 "F.SilkS" user "Ref Des/Silkscreen Top")
		(7 "B.SilkS" user "Ref Des/Silkscreen Bottom")
		(1 "F.Mask" user "Board Geometry/Soldermask Top")
		(3 "B.Mask" user "Board Geometry/Soldermask Bottom")
		(17 "Dwgs.User" user "User.Drawings")
		(19 "Cmts.User" user "User.Comments")
		(21 "Eco1.User" user "User.Eco1")
		(23 "Eco2.User" user "User.Eco2")
		(25 "Edge.Cuts" user "Board Geometry/Outline")
		(27 "Margin" user)
		(31 "F.CrtYd" user "Package Geometry/Place Bound Top")
		(29 "B.CrtYd" user "Package Geometry/Place Bound Bottom")
		(35 "F.Fab" user "Ref Des/Assembly Top")
		(33 "B.Fab" user "Ref Des/Assembly Bottom")
	)
	(footprint ""
		(layer "B.Cu")
		(at 178.10988 -102.707948)
		(property "Reference" "C1942"
			(at 0 0 0)
			(layer "B.SilkS")
			(hide yes)
			(effects
				(font
					(size 1.27 1.27)
				)
				(justify mirror)
			)
		)
		(property "Value" ""
			(at 0 0 0)
			(layer "B.Fab")
			(effects
				(font
					(size 1.27 1.27)
				)
				(justify mirror)
			)
		)
		(duplicate_pad_numbers_are_jumpers no)
		(fp_line
			(start -0.7874 -0.4064)
			(end -0.7874 0.4064)
			(stroke
				(width 0.1524)
				(type default)
			)
			(layer "B.SilkS")
		)
		(fp_line
			(start -0.7874 0.4064)
			(end 0.7874 0.4064)
			(stroke
				(width 0.1524)
				(type default)
			)
			(layer "B.SilkS")
		)
		(fp_line
			(start 0.7874 -0.4064)
			(end -0.7874 -0.4064)
			(stroke
				(width 0.1524)
				(type default)
			)
			(layer "B.SilkS")
		)
		(fp_line
			(start 0.7874 0.4064)
			(end 0.7874 -0.4064)
			(stroke
				(width 0.1524)
				(type default)
			)
			(layer "B.SilkS")
		)
		(fp_line
			(start -0.67945 -0.3048)
			(end -0.67945 0.3048)
			(stroke
				(width 0.1)
				(type default)
			)
			(layer "B.Fab")
		)
		(fp_line
			(start -0.67945 0.3048)
			(end -0.120396 0.3048)
			(stroke
				(width 0.1)
				(type default)
			)
			(layer "B.Fab")
		)
		(fp_line
			(start -0.12065 -0.3048)
			(end -0.67945 -0.3048)
			(stroke
				(width 0.1)
				(type default)
			)
			(layer "B.Fab")
		)
		(fp_line
			(start -0.12065 -0.2794)
			(end -0.12065 -0.3048)
			(stroke
				(width 0.1)
				(type default)
			)
			(layer "B.Fab")
		)
		(fp_line
			(start -0.120396 0.2794)
			(end 0.12065 0.2794)
			(stroke
				(width 0.1)
				(type default)
			)
			(layer "B.Fab")
		)
		(fp_line
			(start -0.120396 0.3048)
			(end -0.120396 0.2794)
			(stroke
				(width 0.1)
				(type default)
			)
			(layer "B.Fab")
		)
		(fp_line
			(start 0.12065 -0.305054)
			(end 0.12065 -0.2794)
			(stroke
				(width 0.1)
				(type default)
			)
			(layer "B.Fab")
		)
		(fp_line
			(start 0.12065 -0.2794)
			(end -0.12065 -0.2794)
			(stroke
				(width 0.1)
				(type default)
			)
			(layer "B.Fab")
		)
		(fp_line
			(start 0.12065 0.2794)
			(end 0.12065 0.3048)
			(stroke
				(width 0.1)
				(type default)
			)
			(layer "B.Fab")
		)
		(fp_line
			(start 0.12065 0.3048)
			(end 0.67945 0.3048)
			(stroke
				(width 0.1)
				(type default)
			)
			(layer "B.Fab")
		)
		(fp_line
			(start 0.67945 -0.305054)
			(end 0.12065 -0.305054)
			(stroke
				(width 0.1)
				(type default)
			)
			(layer "B.Fab")
		)
		(fp_line
			(start 0.67945 0.3048)
			(end 0.67945 -0.305054)
			(stroke
				(width 0.1)
				(type default)
			)
			(layer "B.Fab")
		)
		(pad "1" smd circle
			(at 0.40005 0 180)
			(size 0 0)
			(layers "B.Cu" "B.Mask" "B.Paste")
			(net "P3V3_AUX_FPGA_VCCIO4")
		)
		(pad "2" smd circle
			(at -0.40005 0 180)
			(size 0 0)
			(layers "B.Cu" "B.Mask" "B.Paste")
			(net "GND")
		)
	)
	(footprint ""
		(layer "B.Cu")
		(at 53.095652 -177.349404 180)
		(property "Reference" "PC433"
			(at 0 0 0)
			(layer "B.SilkS")
			(hide yes)
			(effects
				(font
					(size 1.27 1.27)
				)
				(justify mirror)
			)
		)
		(property "Value" ""
			(at 0 0 0)
			(layer "B.Fab")
			(effects
				(font
					(size 1.27 1.27)
				)
				(justify mirror)
			)
		)
		(duplicate_pad_numbers_are_jumpers no)
		(fp_line
			(start 1.524 0.762)
			(end 1.524 -0.762)
			(stroke
				(width 0.1524)
				(type default)
			)
			(layer "B.SilkS")
		)
		(fp_line
			(start 1.524 -0.762)
			(end -1.524 -0.762)
			(stroke
				(width 0.1524)
				(type default)
			)
			(layer "B.SilkS")
		)
		(fp_line
			(start -1.524 0.762)
			(end 1.524 0.762)
			(stroke
				(width 0.1524)
				(type default)
			)
			(layer "B.SilkS")
		)
		(fp_line
			(start -1.524 -0.762)
			(end -1.524 0.762)
			(stroke
				(width 0.1524)
				(type default)
			)
			(layer "B.SilkS")
		)
		(fp_line
			(start 1.1049 0.724916)
			(end -1.1049 0.724916)
			(stroke
				(width 0.1)
				(type default)
			)
			(layer "B.Fab")
		)
		(fp_line
			(start 1.1049 -0.724916)
			(end 1.1049 0.724916)
			(stroke
				(width 0.1)
				(type default)
			)
			(layer "B.Fab")
		)
		(fp_line
			(start -1.1049 0.724916)
			(end -1.1049 -0.724916)
			(stroke
				(width 0.1)
				(type default)
			)
			(layer "B.Fab")
		)
		(fp_line
			(start -1.1049 -0.724916)
			(end 1.1049 -0.724916)
			(stroke
				(width 0.1)
				(type default)
			)
			(layer "B.Fab")
		)
		(pad "1" smd rect
			(at 0.889 0 180)
			(size 1.016 1.27)
			(layers "B.Cu" "B.Mask" "B.Paste")
			(net "SW_P12V_PVCCINFAON_CPU1_FLT")
		)
		(pad "2" smd rect
			(at -0.889 0 180)
			(size 1.016 1.27)
			(layers "B.Cu" "B.Mask" "B.Paste")
			(net "GND")
		)
	)
	(footprint ""
		(layer "B.Cu")
		(at 113.91773 -415.671254)
		(property "Reference" "C2332"
			(at 0 0 0)
			(layer "B.SilkS")
			(hide yes)
			(effects
				(font
					(size 1.27 1.27)
				)
				(justify mirror)
			)
		)
		(property "Value" ""
			(at 0 0 0)
			(layer "B.Fab")
			(effects
				(font
					(size 1.27 1.27)
				)
				(justify mirror)
			)
		)
		(duplicate_pad_numbers_are_jumpers no)
		(fp_line
			(start -1.2954 -0.5842)
			(end -1.2954 0.5842)
			(stroke
				(width 0.1524)
				(type default)
			)
			(layer "B.SilkS")
		)
		(fp_line
			(start -1.2954 0.5842)
			(end 1.2954 0.5842)
			(stroke
				(width 0.1524)
				(type default)
			)
			(layer "B.SilkS")
		)
		(fp_line
			(start 0 -0.5842)
			(end 0 0.5842)
			(stroke
				(width 0.1524)
				(type default)
			)
			(layer "B.SilkS")
		)
		(fp_line
			(start 1.2954 -0.5842)
			(end -1.2954 -0.5842)
			(stroke
				(width 0.1524)
				(type default)
			)
			(layer "B.SilkS")
		)
		(fp_line
			(start 1.2954 0.5842)
			(end 1.2954 -0.5842)
			(stroke
				(width 0.1524)
				(type default)
			)
			(layer "B.SilkS")
		)
		(fp_line
			(start -1.1938 -0.4064)
			(end -1.1938 0.4064)
			(stroke
				(width 0.1)
				(type default)
			)
			(layer "B.Fab")
		)
		(fp_line
			(start -1.1938 0.4064)
			(end -0.8636 0.4064)
			(stroke
				(width 0.1)
				(type default)
			)
			(layer "B.Fab")
		)
		(fp_line
			(start -0.8636 -0.4572)
			(end -0.8636 -0.4064)
			(stroke
				(width 0.1)
				(type default)
			)
			(layer "B.Fab")
		)
		(fp_line
			(start -0.8636 -0.4064)
			(end -1.1938 -0.4064)
			(stroke
				(width 0.1)
				(type default)
			)
			(layer "B.Fab")
		)
		(fp_line
			(start -0.8636 0.4064)
			(end -0.8636 0.4572)
			(stroke
				(width 0.1)
				(type default)
			)
			(layer "B.Fab")
		)
		(fp_line
			(start -0.8636 0.4572)
			(end 0.8636 0.4572)
			(stroke
				(width 0.1)
				(type default)
			)
			(layer "B.Fab")
		)
		(fp_line
			(start 0.8636 -0.4572)
			(end -0.8636 -0.4572)
			(stroke
				(width 0.1)
				(type default)
			)
			(layer "B.Fab")
		)
		(fp_line
			(start 0.8636 -0.4064)
			(end 0.8636 -0.4572)
			(stroke
				(width 0.1)
				(type default)
			)
			(layer "B.Fab")
		)
		(fp_line
			(start 0.8636 0.4064)
			(end 1.1938 0.4064)
			(stroke
				(width 0.1)
				(type default)
			)
			(layer "B.Fab")
		)
		(fp_line
			(start 0.8636 0.4572)
			(end 0.8636 0.4064)
			(stroke
				(width 0.1)
				(type default)
			)
			(layer "B.Fab")
		)
		(fp_line
			(start 1.1938 -0.4064)
			(end 0.8636 -0.4064)
			(stroke
				(width 0.1)
				(type default)
			)
			(layer "B.Fab")
		)
		(fp_line
			(start 1.1938 0.4064)
			(end 1.1938 -0.4064)
			(stroke
				(width 0.1)
				(type default)
			)
			(layer "B.Fab")
		)
		(pad "1" smd rect
			(at 0.7366 0 270)
			(size 0.7112 0.8128)
			(layers "B.Cu" "B.Mask" "B.Paste")
			(net "P3V3_9ZXL045_VDDR")
		)
		(pad "2" smd rect
			(at -0.7366 0 270)
			(size 0.7112 0.8128)
			(layers "B.Cu" "B.Mask" "B.Paste")
			(net "GND")
		)
	)
)
